(kicad_pcb
	(version 20260206)
	(generator "pcbnew")
	(generator_version "10.0")
	(general
		(thickness 1.6)
		(legacy_teardrops no)
	)
	(paper "A4")
	(title_block
		(title "baseboard — 13948-1b.1110WZS1818.brd")
		(comment 1 "Honey Badger (Wiwynn) / footprints 661-667 of 2523")
	)
	(layers
		(0 "F.Cu" signal "TOP")
		(4 "In1.Cu" signal "L2GND")
		(6 "In2.Cu" signal "L3")
		(8 "In3.Cu" signal "L4VCC")
		(10 "In4.Cu" signal "L5VCC")
		(12 "In5.Cu" signal "L6")
		(14 "In6.Cu" signal "L7GND")
		(2 "B.Cu" signal "BOTTOM")
		(9 "F.Adhes" user "F.Adhesive")
		(11 "B.Adhes" user "B.Adhesive")
		(13 "F.Paste" user "Package Geometry/Pastemask Top")
		(15 "B.Paste" user "Package Geometry/Pastemask Bottom")
		(5 "F.SilkS" user "Ref Des/Silkscreen Top")
		(7 "B.SilkS" user "Ref Des/Silkscreen Bottom")
		(1 "F.Mask" user "Board Geometry/Soldermask Top")
		(3 "B.Mask" user "Board Geometry/Soldermask Bottom")
		(17 "Dwgs.User" user "User.Drawings")
		(19 "Cmts.User" user "User.Comments")
		(21 "Eco1.User" user "User.Eco1")
		(23 "Eco2.User" user "User.Eco2")
		(25 "Edge.Cuts" user "Board Geometry/Outline")
		(27 "Margin" user)
		(31 "F.CrtYd" user "Package Geometry/Place Bound Top")
		(29 "B.CrtYd" user "Package Geometry/Place Bound Bottom")
		(35 "F.Fab" user "Ref Des/Assembly Top")
		(33 "B.Fab" user "Ref Des/Assembly Bottom")
	)
	(footprint ""
		(layer "F.Cu")
		(at 350.484948 -12.999974 180)
		(property "Reference" "SW1"
			(at 0 0 180)
			(layer "F.SilkS")
			(hide yes)
			(effects
				(font
					(size 1.27 1.27)
				)
			)
		)
		(property "Value" "SW-TACT-4P-185-GP"
			(at -5.746242 -1.509776 180)
			(unlocked yes)
			(layer "F.Fab")
			(hide yes)
			(effects
				(font
					(size 1.016 1.016)
					(thickness 0.1524)
				)
			)
		)
		(property "Device Type" "DTS-65K-S-V"
			(at -5.746242 -3.033776 180)
			(unlocked yes)
			(layer "F.Fab")
			(hide yes)
			(effects
				(font
					(size 1.016 1.016)
					(thickness 0.1524)
				)
			)
		)
		(duplicate_pad_numbers_are_jumpers no)
		(fp_line
			(start 4.2164 3.3528)
			(end 4.2164 -3.3528)
			(stroke
				(width 0.1524)
				(type default)
			)
			(layer "F.SilkS")
		)
		(fp_line
			(start 4.2164 -3.3528)
			(end -4.2164 -3.3528)
			(stroke
				(width 0.1524)
				(type default)
			)
			(layer "F.SilkS")
		)
		(fp_line
			(start 0 0.762)
			(end 0 2.54)
			(stroke
				(width 0.1524)
				(type default)
			)
			(layer "F.SilkS")
		)
		(fp_line
			(start 0 -0.762)
			(end 0.508 0.508)
			(stroke
				(width 0.1524)
				(type default)
			)
			(layer "F.SilkS")
		)
		(fp_line
			(start 0 -2.54)
			(end 0 -0.762)
			(stroke
				(width 0.1524)
				(type default)
			)
			(layer "F.SilkS")
		)
		(fp_line
			(start -3.2258 -3.6322)
			(end -4.4958 -3.6322)
			(stroke
				(width 0.4064)
				(type default)
			)
			(layer "F.SilkS")
		)
		(fp_line
			(start -4.2164 3.3528)
			(end 4.2164 3.3528)
			(stroke
				(width 0.1524)
				(type default)
			)
			(layer "F.SilkS")
		)
		(fp_line
			(start -4.2164 -3.3528)
			(end -4.2164 3.3528)
			(stroke
				(width 0.1524)
				(type default)
			)
			(layer "F.SilkS")
		)
		(fp_line
			(start -4.4958 -3.6322)
			(end -4.4958 -2.3622)
			(stroke
				(width 0.4064)
				(type default)
			)
			(layer "F.SilkS")
		)
		(fp_circle
			(center 3.24993 2.249932)
			(end 2.18313 2.249932)
			(stroke
				(width 0.3048)
				(type default)
			)
			(fill no)
			(layer "F.SilkS")
		)
		(fp_circle
			(center 3.24993 -2.249932)
			(end 2.18313 -2.249932)
			(stroke
				(width 0.3048)
				(type default)
			)
			(fill no)
			(layer "F.SilkS")
		)
		(fp_circle
			(center 0 0.762)
			(end -0.0762 0.762)
			(stroke
				(width 0.1524)
				(type default)
			)
			(fill no)
			(layer "F.SilkS")
		)
		(fp_circle
			(center 0 -0.762)
			(end -0.0762 -0.762)
			(stroke
				(width 0.1524)
				(type default)
			)
			(fill no)
			(layer "F.SilkS")
		)
		(fp_circle
			(center -3.24993 2.249932)
			(end -4.31673 2.249932)
			(stroke
				(width 0.3048)
				(type default)
			)
			(fill no)
			(layer "F.SilkS")
		)
		(fp_circle
			(center -3.24993 -2.249932)
			(end -4.31673 -2.249932)
			(stroke
				(width 0.3048)
				(type default)
			)
			(fill no)
			(layer "F.SilkS")
		)
		(fp_poly
			(pts
				(xy -3.0988 3.0988) (xy -3.0988 2.605532) (xy -3.9497 2.605532) (xy -3.9497 1.894332) (xy -3.0988 1.894332)
				(xy -3.0988 -1.894332) (xy -3.9497 -1.894332) (xy -3.9497 -2.605532) (xy -3.0988 -2.605532) (xy -3.0988 -3.0988)
				(xy 3.0988 -3.0988) (xy 3.0988 -2.605532) (xy 3.9497 -2.605532) (xy 3.9497 -1.894332) (xy 3.0988 -1.894332)
				(xy 3.0988 1.894332) (xy 3.9497 1.894332) (xy 3.9497 2.605532) (xy 3.0988 2.605532) (xy 3.0988 3.0988)
			)
			(stroke
				(width 0)
				(type default)
			)
			(fill no)
			(layer "F.CrtYd")
		)
		(fp_poly
			(pts
				(xy -4.4704 3.6068) (xy -4.4704 -3.6068) (xy 4.4704 -3.6068) (xy 4.4704 3.6068) (xy 0.00254 3.6068)
				(xy 0.00254 3.0988) (xy 3.0988 3.0988) (xy 3.0988 2.605532) (xy 3.9497 2.605532) (xy 3.9497 1.894332)
				(xy 3.0988 1.894332) (xy 3.0988 -1.894332) (xy 3.9497 -1.894332) (xy 3.9497 -2.605532) (xy 3.0988 -2.605532)
				(xy 3.0988 -3.0988) (xy -3.0988 -3.0988) (xy -3.0988 -2.605532) (xy -3.9497 -2.605532) (xy -3.9497 -1.894332)
				(xy -3.0988 -1.894332) (xy -3.0988 1.894332) (xy -3.9497 1.894332) (xy -3.9497 2.605532) (xy -3.0988 2.605532)
				(xy -3.0988 3.0988) (xy -0.00254 3.0988) (xy -0.00254 3.6068)
			)
			(stroke
				(width 0)
				(type default)
			)
			(fill no)
			(layer "F.CrtYd")
		)
		(fp_rect
			(start -4.4704 3.6068)
			(end 4.4704 -3.6068)
			(stroke
				(width 0)
				(type default)
			)
			(fill no)
			(layer "F.Fab")
		)
		(pad "1" thru_hole circle
			(at -3.24993 -2.249932 180)
			(size 1.4224 1.4224)
			(drill 1.016)
			(layers "*.Cu" "*.Mask")
			(remove_unused_layers no)
			(net "FP_PWR_BTN_N")
			(clearance 0.1524)
			(thermal_gap 0.1524)
		)
		(pad "2" thru_hole circle
			(at 3.24993 -2.249932 180)
			(size 1.4224 1.4224)
			(drill 1.016)
			(layers "*.Cu" "*.Mask")
			(remove_unused_layers no)
			(net "FP_PWR_BTN_N")
			(clearance 0.1524)
			(thermal_gap 0.1524)
		)
		(pad "3" thru_hole circle
			(at -3.24993 2.249932 180)
			(size 1.4224 1.4224)
			(drill 1.016)
			(layers "*.Cu" "*.Mask")
			(remove_unused_layers no)
			(net "GND")
			(clearance 0.1524)
			(thermal_gap 0.1524)
		)
		(pad "4" thru_hole circle
			(at 3.24993 2.249932 180)
			(size 1.4224 1.4224)
			(drill 1.016)
			(layers "*.Cu" "*.Mask")
			(remove_unused_layers no)
			(net "GND")
			(clearance 0.1524)
			(thermal_gap 0.1524)
		)
	)
	(footprint ""
		(layer "F.Cu")
		(at 341.249 -100.203)
		(property "Reference" "PL1"
			(at 0 0 0)
			(layer "F.SilkS")
			(hide yes)
			(effects
				(font
					(size 1.27 1.27)
				)
			)
		)
		(property "Value" "COIL-6D8UH-10-GP"
			(at -4.699 -4.0132 0)
			(unlocked yes)
			(layer "F.Fab")
			(hide yes)
			(effects
				(font
					(size 1.016 1.016)
					(thickness 0.1524)
				)
			)
		)
		(property "Device Type" "L7066-1830-UH119"
			(at -4.699 -5.5372 0)
			(unlocked yes)
			(layer "F.Fab")
			(hide yes)
			(effects
				(font
					(size 1.016 1.016)
					(thickness 0.1524)
				)
			)
		)
		(duplicate_pad_numbers_are_jumpers no)
		(fp_line
			(start -3.556 -4.4958)
			(end 3.556 -4.4958)
			(stroke
				(width 0.1524)
				(type default)
			)
			(layer "F.SilkS")
		)
		(fp_line
			(start -3.556 4.4958)
			(end -3.556 -4.4958)
			(stroke
				(width 0.1524)
				(type default)
			)
			(layer "F.SilkS")
		)
		(fp_line
			(start 3.556 -4.4958)
			(end 3.556 4.4958)
			(stroke
				(width 0.1524)
				(type default)
			)
			(layer "F.SilkS")
		)
		(fp_line
			(start 3.556 4.4958)
			(end -3.556 4.4958)
			(stroke
				(width 0.1524)
				(type default)
			)
			(layer "F.SilkS")
		)
		(fp_rect
			(start -3.302 3.4798)
			(end 3.302 -3.4798)
			(stroke
				(width 0)
				(type default)
			)
			(fill no)
			(layer "F.CrtYd")
		)
		(fp_poly
			(pts
				(xy -3.81 4.572) (xy -3.81 -4.572) (xy 3.81 -4.572) (xy 3.81 -0.5588) (xy 3.302 -0.5588) (xy 3.302 -3.4798)
				(xy -3.302 -3.4798) (xy -3.302 3.4798) (xy 3.302 3.4798) (xy 3.302 -0.5461) (xy 3.81 -0.5461) (xy 3.81 4.572)
			)
			(stroke
				(width 0)
				(type default)
			)
			(fill no)
			(layer "F.CrtYd")
		)
		(fp_rect
			(start -3.81 4.572)
			(end 3.81 -4.572)
			(stroke
				(width 0)
				(type default)
			)
			(fill no)
			(layer "F.Fab")
		)
		(pad "1" smd rect
			(at 0 -2.779522)
			(size 3.5052 2.921)
			(layers "F.Cu" "F.Mask" "F.Paste")
			(net "P5V_STBY_SW")
		)
		(pad "2" smd rect
			(at 0 2.779522)
			(size 3.5052 2.921)
			(layers "F.Cu" "F.Mask" "F.Paste")
			(net "P5V_STBY")
		)
	)
	(footprint ""
		(layer "F.Cu")
		(at 59.594242 -144.191482)
		(property "Reference" "SR785"
			(at 0 0 0)
			(layer "F.SilkS")
			(hide yes)
			(effects
				(font
					(size 1.27 1.27)
				)
			)
		)
		(property "Value" "10KR2F-2-GP"
			(at 0.064008 -3.993896 0)
			(unlocked yes)
			(layer "F.Fab")
			(hide yes)
			(effects
				(font
					(size 1.016 1.016)
					(thickness 0.1524)
				)
			)
		)
		(property "Device Type" "R402H16"
			(at 0.064008 -5.517896 0)
			(unlocked yes)
			(layer "F.Fab")
			(hide yes)
			(effects
				(font
					(size 1.016 1.016)
					(thickness 0.1524)
				)
			)
		)
		(duplicate_pad_numbers_are_jumpers no)
		(fp_line
			(start -0.508 -0.9398)
			(end -0.508 0.9398)
			(stroke
				(width 0.1524)
				(type default)
			)
			(layer "F.SilkS")
		)
		(fp_line
			(start 0.508 -0.9398)
			(end -0.508 -0.9398)
			(stroke
				(width 0.1524)
				(type default)
			)
			(layer "F.SilkS")
		)
		(fp_rect
			(start -0.508 0.9398)
			(end 0.508 -0.9398)
			(stroke
				(width 0)
				(type default)
			)
			(fill no)
			(layer "F.CrtYd")
		)
		(fp_rect
			(start -0.508 0.9398)
			(end 0.508 -0.9398)
			(stroke
				(width 0)
				(type default)
			)
			(fill no)
			(layer "F.Fab")
		)
		(pad "1" smd custom
			(at 0 -0.4445)
			(size 0.1397 0.1397)
			(layers "F.Cu" "F.Mask" "F.Paste")
			(net "P1V8_E")
			(options
				(clearance outline)
				(anchor circle)
			)
			(primitives
				(gr_poly
					(pts
						(arc
							(start -0.1778 -0.2794)
							(mid -0.249642 -0.249642)
							(end -0.2794 -0.1778)
						)
						(arc
							(start -0.2794 0.1778)
							(mid -0.249642 0.249642)
							(end -0.1778 0.2794)
						)
						(arc
							(start 0.1778 0.2794)
							(mid 0.249642 0.249642)
							(end 0.2794 0.1778)
						)
						(arc
							(start 0.2794 -0.1778)
							(mid 0.249642 -0.249642)
							(end 0.1778 -0.2794)
						)
					)
					(width 0)
					(fill yes)
				)
			)
		)
		(pad "2" smd custom
			(at 0 0.4445)
			(size 0.1397 0.1397)
			(layers "F.Cu" "F.Mask" "F.Paste")
			(net "EXP_XM_CS_N_0")
			(options
				(clearance outline)
				(anchor circle)
			)
			(primitives
				(gr_poly
					(pts
						(arc
							(start -0.1778 -0.2794)
							(mid -0.249642 -0.249642)
							(end -0.2794 -0.1778)
						)
						(arc
							(start -0.2794 0.1778)
							(mid -0.249642 0.249642)
							(end -0.1778 0.2794)
						)
						(arc
							(start 0.1778 0.2794)
							(mid 0.249642 0.249642)
							(end 0.2794 0.1778)
						)
						(arc
							(start 0.2794 -0.1778)
							(mid 0.249642 -0.249642)
							(end 0.1778 -0.2794)
						)
					)
					(width 0)
					(fill yes)
				)
			)
		)
	)
	(footprint ""
		(layer "F.Cu")
		(at 172.268388 -31.646368)
		(property "Reference" "R401"
			(at 0 0 0)
			(layer "F.SilkS")
			(hide yes)
			(effects
				(font
					(size 1.27 1.27)
				)
			)
		)
		(property "Value" "49D9R2F-GP"
			(at 0.064008 -3.993896 0)
			(unlocked yes)
			(layer "F.Fab")
			(hide yes)
			(effects
				(font
					(size 1.016 1.016)
					(thickness 0.1524)
				)
			)
		)
		(property "Device Type" "R402H16"
			(at 0.064008 -5.517896 0)
			(unlocked yes)
			(layer "F.Fab")
			(hide yes)
			(effects
				(font
					(size 1.016 1.016)
					(thickness 0.1524)
				)
			)
		)
		(duplicate_pad_numbers_are_jumpers no)
		(fp_line
			(start -0.508 -0.9398)
			(end -0.508 0.9398)
			(stroke
				(width 0.1524)
				(type default)
			)
			(layer "F.SilkS")
		)
		(fp_line
			(start 0.508 -0.9398)
			(end -0.508 -0.9398)
			(stroke
				(width 0.1524)
				(type default)
			)
			(layer "F.SilkS")
		)
		(fp_rect
			(start -0.508 0.9398)
			(end 0.508 -0.9398)
			(stroke
				(width 0)
				(type default)
			)
			(fill no)
			(layer "F.CrtYd")
		)
		(fp_rect
			(start -0.508 0.9398)
			(end 0.508 -0.9398)
			(stroke
				(width 0)
				(type default)
			)
			(fill no)
			(layer "F.Fab")
		)
		(pad "1" smd custom
			(at 0 -0.4445)
			(size 0.1397 0.1397)
			(layers "F.Cu" "F.Mask" "F.Paste")
			(net "MOD_IMC_FAB_D_COP")
			(options
				(clearance outline)
				(anchor circle)
			)
			(primitives
				(gr_poly
					(pts
						(arc
							(start -0.1778 -0.2794)
							(mid -0.249642 -0.249642)
							(end -0.2794 -0.1778)
						)
						(arc
							(start -0.2794 0.1778)
							(mid -0.249642 0.249642)
							(end -0.1778 0.2794)
						)
						(arc
							(start 0.1778 0.2794)
							(mid 0.249642 0.249642)
							(end 0.2794 0.1778)
						)
						(arc
							(start 0.2794 -0.1778)
							(mid 0.249642 -0.249642)
							(end 0.1778 -0.2794)
						)
					)
					(width 0)
					(fill yes)
				)
			)
		)
		(pad "2" smd custom
			(at 0 0.4445)
			(size 0.1397 0.1397)
			(layers "F.Cu" "F.Mask" "F.Paste")
			(net "BCM5221_RX_C_DP")
			(options
				(clearance outline)
				(anchor circle)
			)
			(primitives
				(gr_poly
					(pts
						(arc
							(start -0.1778 -0.2794)
							(mid -0.249642 -0.249642)
							(end -0.2794 -0.1778)
						)
						(arc
							(start -0.2794 0.1778)
							(mid -0.249642 0.249642)
							(end -0.1778 0.2794)
						)
						(arc
							(start 0.1778 0.2794)
							(mid 0.249642 0.249642)
							(end 0.2794 0.1778)
						)
						(arc
							(start 0.2794 -0.1778)
							(mid 0.249642 -0.249642)
							(end 0.1778 -0.2794)
						)
					)
					(width 0)
					(fill yes)
				)
			)
		)
	)
	(footprint ""
		(layer "F.Cu")
		(at 146.939 -16.764 -90)
		(property "Reference" "C324"
			(at 0 0 270)
			(layer "F.SilkS")
			(hide yes)
			(effects
				(font
					(size 1.27 1.27)
				)
			)
		)
		(property "Value" "SCD1U16V2KX-3GP"
			(at 1.1811 -2.7051 270)
			(unlocked yes)
			(layer "F.Fab")
			(hide yes)
			(effects
				(font
					(size 1.016 1.016)
					(thickness 0.1524)
				)
			)
		)
		(property "Device Type" "C402H22"
			(at 1.1811 -4.2291 270)
			(unlocked yes)
			(layer "F.Fab")
			(hide yes)
			(effects
				(font
					(size 1.016 1.016)
					(thickness 0.1524)
				)
			)
		)
		(duplicate_pad_numbers_are_jumpers no)
		(fp_rect
			(start -0.4318 0.9525)
			(end 0.4318 -0.9525)
			(stroke
				(width 0)
				(type default)
			)
			(fill no)
			(layer "F.CrtYd")
		)
		(fp_rect
			(start -0.4318 0.9525)
			(end 0.4318 -0.9525)
			(stroke
				(width 0)
				(type default)
			)
			(fill no)
			(layer "F.Fab")
		)
		(pad "1" smd custom
			(at 0 -0.4445 270)
			(size 0.1524 0.1524)
			(layers "F.Cu" "F.Mask" "F.Paste")
			(net "PHY_AVDD")
			(options
				(clearance outline)
				(anchor circle)
			)
			(primitives
				(gr_poly
					(pts
						(arc
							(start 0.3048 -0.2032)
							(mid 0.275042 -0.275042)
							(end 0.2032 -0.3048)
						)
						(arc
							(start -0.2032 -0.3048)
							(mid -0.275042 -0.275042)
							(end -0.3048 -0.2032)
						)
						(arc
							(start -0.3048 0.2032)
							(mid -0.275042 0.275042)
							(end -0.2032 0.3048)
						)
						(arc
							(start 0.2032 0.3048)
							(mid 0.275042 0.275042)
							(end 0.3048 0.2032)
						)
					)
					(width 0)
					(fill yes)
				)
			)
		)
		(pad "2" smd custom
			(at 0 0.4445 270)
			(size 0.1524 0.1524)
			(layers "F.Cu" "F.Mask" "F.Paste")
			(net "GND")
			(options
				(clearance outline)
				(anchor circle)
			)
			(primitives
				(gr_poly
					(pts
						(arc
							(start 0.3048 -0.2032)
							(mid 0.275042 -0.275042)
							(end 0.2032 -0.3048)
						)
						(arc
							(start -0.2032 -0.3048)
							(mid -0.275042 -0.275042)
							(end -0.3048 -0.2032)
						)
						(arc
							(start -0.3048 0.2032)
							(mid -0.275042 0.275042)
							(end -0.2032 0.3048)
						)
						(arc
							(start 0.2032 0.3048)
							(mid 0.275042 0.275042)
							(end 0.3048 0.2032)
						)
					)
					(width 0)
					(fill yes)
				)
			)
		)
	)
	(footprint ""
		(layer "F.Cu")
		(at 290.068 -158.496 180)
		(property "Reference" "R422"
			(at 0 0 180)
			(layer "F.SilkS")
			(hide yes)
			(effects
				(font
					(size 1.27 1.27)
				)
			)
		)
		(property "Value" "2K2R2J-2-GP"
			(at 0.064008 -3.993896 180)
			(unlocked yes)
			(layer "F.Fab")
			(hide yes)
			(effects
				(font
					(size 1.016 1.016)
					(thickness 0.1524)
				)
			)
		)
		(property "Device Type" "R402H16"
			(at 0.064008 -5.517896 180)
			(unlocked yes)
			(layer "F.Fab")
			(hide yes)
			(effects
				(font
					(size 1.016 1.016)
					(thickness 0.1524)
				)
			)
		)
		(duplicate_pad_numbers_are_jumpers no)
		(fp_line
			(start 0.508 -0.9398)
			(end -0.508 -0.9398)
			(stroke
				(width 0.1524)
				(type default)
			)
			(layer "F.SilkS")
		)
		(fp_line
			(start -0.508 -0.9398)
			(end -0.508 0.9398)
			(stroke
				(width 0.1524)
				(type default)
			)
			(layer "F.SilkS")
		)
		(fp_rect
			(start -0.508 0.9398)
			(end 0.508 -0.9398)
			(stroke
				(width 0)
				(type default)
			)
			(fill no)
			(layer "F.CrtYd")
		)
		(fp_rect
			(start -0.508 0.9398)
			(end 0.508 -0.9398)
			(stroke
				(width 0)
				(type default)
			)
			(fill no)
			(layer "F.Fab")
		)
		(pad "1" smd custom
			(at 0 -0.4445 180)
			(size 0.1397 0.1397)
			(layers "F.Cu" "F.Mask" "F.Paste")
			(net "P3V3_STBY")
			(options
				(clearance outline)
				(anchor circle)
			)
			(primitives
				(gr_poly
					(pts
						(arc
							(start -0.1778 -0.2794)
							(mid -0.249642 -0.249642)
							(end -0.2794 -0.1778)
						)
						(arc
							(start -0.2794 0.1778)
							(mid -0.249642 0.249642)
							(end -0.1778 0.2794)
						)
						(arc
							(start 0.1778 0.2794)
							(mid 0.249642 0.249642)
							(end 0.2794 0.1778)
						)
						(arc
							(start 0.2794 -0.1778)
							(mid 0.249642 -0.249642)
							(end 0.1778 -0.2794)
						)
					)
					(width 0)
					(fill yes)
				)
			)
		)
		(pad "2" smd custom
			(at 0 0.4445 180)
			(size 0.1397 0.1397)
			(layers "F.Cu" "F.Mask" "F.Paste")
			(net "CPU_BMC_UART_RX")
			(options
				(clearance outline)
				(anchor circle)
			)
			(primitives
				(gr_poly
					(pts
						(arc
							(start -0.1778 -0.2794)
							(mid -0.249642 -0.249642)
							(end -0.2794 -0.1778)
						)
						(arc
							(start -0.2794 0.1778)
							(mid -0.249642 0.249642)
							(end -0.1778 0.2794)
						)
						(arc
							(start 0.1778 0.2794)
							(mid 0.249642 0.249642)
							(end 0.2794 0.1778)
						)
						(arc
							(start 0.2794 -0.1778)
							(mid 0.249642 -0.249642)
							(end 0.1778 -0.2794)
						)
					)
					(width 0)
					(fill yes)
				)
			)
		)
	)
	(footprint ""
		(layer "F.Cu")
		(at 108.458 -28.194)
		(property "Reference" "STP43"
			(at 0 0 0)
			(layer "F.SilkS")
			(hide yes)
			(effects
				(font
					(size 1.27 1.27)
				)
			)
		)
		(property "Value" "TPAD28"
			(at 0.0127 -1.8034 0)
			(unlocked yes)
			(layer "F.Fab")
			(hide yes)
			(effects
				(font
					(size 1.016 1.016)
					(thickness 0.1524)
				)
			)
		)
		(property "Device Type" "TPAD28"
			(at 0.0127 -3.3274 0)
			(unlocked yes)
			(layer "F.Fab")
			(hide yes)
			(effects
				(font
					(size 1.016 1.016)
					(thickness 0.1524)
				)
			)
		)
		(duplicate_pad_numbers_are_jumpers no)
		(fp_poly
			(pts
				(arc
					(start 0.3556 0)
					(mid -0.3556 0)
					(end 0.3556 0)
				)
			)
			(stroke
				(width 0)
				(type default)
			)
			(fill no)
			(layer "F.CrtYd")
		)
		(fp_poly
			(pts
				(arc
					(start 0.6096 0)
					(mid -0.6096 0)
					(end 0.6096 0)
				)
			)
			(stroke
				(width 0)
				(type default)
			)
			(fill no)
			(layer "F.Fab")
		)
		(pad "1" smd circle
			(at 0 0)
			(size 0.7112 0.7112)
			(layers "F.Cu" "F.Mask" "F.Paste")
			(net "SYS_DBMODE1")
		)
	)
)
